(kicad_pcb
	(version 20241229)
	(generator "pcbnew")
	(generator_version "9.0")
	(general
		(thickness 1.711)
		(legacy_teardrops no)
	)
	(paper "A4")
	(title_block
		(title "Antmicro Baseboard for Jetson AGX Thor")
		(date "2026-02-18")
		(rev "1.1.0")
		(company "Antmicro Ltd")
		(comment 1 "www.antmicro.com")
		(comment 9 "footprints 89-92 of 1170")
	)
	(layers
		(0 "F.Cu" signal)
		(4 "In1.Cu" signal)
		(6 "In2.Cu" signal)
		(8 "In3.Cu" signal)
		(10 "In4.Cu" jumper)
		(12 "In5.Cu" signal)
		(14 "In6.Cu" signal)
		(16 "In7.Cu" signal)
		(18 "In8.Cu" signal)
		(2 "B.Cu" signal)
		(9 "F.Adhes" user "F.Adhesive")
		(11 "B.Adhes" user "B.Adhesive")
		(13 "F.Paste" user)
		(15 "B.Paste" user)
		(5 "F.SilkS" user "F.Silkscreen")
		(7 "B.SilkS" user "B.Silkscreen")
		(1 "F.Mask" user)
		(3 "B.Mask" user)
		(17 "Dwgs.User" user "User.Drawings")
		(19 "Cmts.User" user "User.Comments")
		(21 "Eco1.User" user "User.Eco1")
		(23 "Eco2.User" user "User.Eco2")
		(25 "Edge.Cuts" user)
		(27 "Margin" user)
		(31 "F.CrtYd" user "F.Courtyard")
		(29 "B.CrtYd" user "B.Courtyard")
		(35 "F.Fab" user)
		(33 "B.Fab" user)
	)
	(footprint "antmicro-footprints:C_0402_1005Metric"
		(layer "F.Cu")
		(at 214 132.8 180)
		(descr "Capacitor SMD 0402")
		(tags "capacitor SMD 0402")
		(property "Reference" "C195"
			(at -3.67 0.47 0)
			(layer "F.SilkS")
			(effects
				(font
					(size 0.7 0.7)
					(thickness 0.15)
				)
				(justify right top)
			)
		)
		(property "Value" "C_1n_0402"
			(at -1.022927 2.155213 0)
			(layer "F.Fab")
			(effects
				(font
					(size 0.7 0.7)
					(thickness 0.15)
				)
				(justify right top)
			)
		)
		(property "Datasheet" "https://www.murata.com/products/productdetail?partno=GRM1555C1H102JA01%23"
			(at 0 0 0)
			(layer "F.Fab")
			(hide yes)
			(effects
				(font
					(size 1.27 1.27)
					(thickness 0.15)
				)
			)
		)
		(property "Description" "SMD Multilayer Ceramic Capacitor, 1000 pF, 50 V, 0402 [1005 Metric], ± 5%, C0G / NP0, GRM Series"
			(at 0 0 0)
			(layer "F.Fab")
			(hide yes)
			(effects
				(font
					(size 1.27 1.27)
					(thickness 0.15)
				)
			)
		)
		(property "MPN" "GRM1555C1H102JA01D"
			(at 0 0 180)
			(unlocked yes)
			(layer "F.Fab")
			(hide yes)
			(effects
				(font
					(size 1 1)
					(thickness 0.15)
				)
			)
		)
		(property "Manufacturer" "Murata"
			(at 0 0 180)
			(unlocked yes)
			(layer "F.Fab")
			(hide yes)
			(effects
				(font
					(size 1 1)
					(thickness 0.15)
				)
			)
		)
		(property "License" "Apache-2.0"
			(at 0 0 180)
			(unlocked yes)
			(layer "F.Fab")
			(hide yes)
			(effects
				(font
					(size 1 1)
					(thickness 0.15)
				)
			)
		)
		(property "Author" "Antmicro"
			(at 0 0 180)
			(unlocked yes)
			(layer "F.Fab")
			(hide yes)
			(effects
				(font
					(size 1 1)
					(thickness 0.15)
				)
			)
		)
		(property "Val" "1n"
			(at 0 0 180)
			(unlocked yes)
			(layer "F.Fab")
			(hide yes)
			(effects
				(font
					(size 1 1)
					(thickness 0.15)
				)
			)
		)
		(property "Voltage" "50V"
			(at 0 0 180)
			(unlocked yes)
			(layer "F.Fab")
			(hide yes)
			(effects
				(font
					(size 1 1)
					(thickness 0.15)
				)
			)
		)
		(property "Dielectric" "C0G"
			(at 0 0 180)
			(unlocked yes)
			(layer "F.Fab")
			(hide yes)
			(effects
				(font
					(size 1 1)
					(thickness 0.15)
				)
			)
		)
		(sheetname "/USB Hub/")
		(sheetfile "usb_hub.kicad_sch")
		(attr smd)
		(fp_rect
			(start -0.925 -0.47)
			(end 0.925 0.47)
			(stroke
				(width 0.05)
				(type default)
			)
			(fill no)
			(layer "F.CrtYd")
		)
		(fp_line
			(start 0.504 0.248)
			(end -0.494 0.248)
			(stroke
				(width 0.15)
				(type solid)
			)
			(layer "F.Fab")
		)
		(fp_line
			(start 0.504 -0.25)
			(end 0.504 0.248)
			(stroke
				(width 0.15)
				(type solid)
			)
			(layer "F.Fab")
		)
		(fp_line
			(start -0.494 0.248)
			(end -0.494 -0.25)
			(stroke
				(width 0.15)
				(type solid)
			)
			(layer "F.Fab")
		)
		(fp_line
			(start -0.494 -0.25)
			(end 0.504 -0.25)
			(stroke
				(width 0.15)
				(type solid)
			)
			(layer "F.Fab")
		)
		(fp_text user "${REFERENCE}"
			(at -0.939 4.599 0)
			(layer "F.Fab")
			(effects
				(font
					(size 0.7 0.7)
					(thickness 0.15)
				)
				(justify right top)
			)
		)
		(fp_text user "License: Apache-2.0"
			(at -0.939 5.799 0)
			(layer "F.Fab")
			(effects
				(font
					(size 0.7 0.7)
					(thickness 0.15)
				)
				(justify right top)
			)
		)
		(fp_text user "Author: Antmicro"
			(at -0.939 3.399 0)
			(layer "F.Fab")
			(effects
				(font
					(size 0.7 0.7)
					(thickness 0.15)
				)
				(justify right top)
			)
		)
		(pad "1" smd roundrect
			(at -0.48 0 180)
			(size 0.59 0.64)
			(layers "F.Cu" "F.Mask" "F.Paste")
			(roundrect_rratio 0.25)
			(net 1 "GND")
			(pintype "passive")
		)
		(pad "2" smd roundrect
			(at 0.48 0 180)
			(size 0.59 0.64)
			(layers "F.Cu" "F.Mask" "F.Paste")
			(roundrect_rratio 0.25)
			(net 527 "/USB Hub/~{RESET}")
			(pintype "passive")
		)
	)
	(footprint "antmicro-footprints:C_0402_1005Metric"
		(layer "F.Cu")
		(at 170.529468 119.216 180)
		(descr "Capacitor SMD 0402")
		(tags "capacitor SMD 0402")
		(property "Reference" "C197"
			(at 6.529468 -0.384 0)
			(layer "F.SilkS")
			(effects
				(font
					(size 0.7 0.7)
					(thickness 0.15)
				)
				(justify left bottom)
			)
		)
		(property "Value" "C_100n_0402"
			(at -1.022927 2.155213 0)
			(layer "F.Fab")
			(effects
				(font
					(size 0.7 0.7)
					(thickness 0.15)
				)
				(justify right top)
			)
		)
		(property "Datasheet" "https://www.murata.com/products/productdetail?partno=GRM155R61H104KE14%23"
			(at 0 0 0)
			(layer "F.Fab")
			(hide yes)
			(effects
				(font
					(size 1.27 1.27)
					(thickness 0.15)
				)
			)
		)
		(property "Description" "SMD Multilayer Ceramic Capacitor, 0.1 µF, 50 V, 0402 [1005 Metric], ± 10%, X5R, GRM Series"
			(at 0 0 0)
			(layer "F.Fab")
			(hide yes)
			(effects
				(font
					(size 1.27 1.27)
					(thickness 0.15)
				)
			)
		)
		(property "MPN" "GRM155R61H104KE14D"
			(at 0 0 180)
			(unlocked yes)
			(layer "F.Fab")
			(hide yes)
			(effects
				(font
					(size 1 1)
					(thickness 0.15)
				)
			)
		)
		(property "Manufacturer" "Murata"
			(at 0 0 180)
			(unlocked yes)
			(layer "F.Fab")
			(hide yes)
			(effects
				(font
					(size 1 1)
					(thickness 0.15)
				)
			)
		)
		(property "License" "Apache-2.0"
			(at 0 0 180)
			(unlocked yes)
			(layer "F.Fab")
			(hide yes)
			(effects
				(font
					(size 1 1)
					(thickness 0.15)
				)
			)
		)
		(property "Author" "Antmicro"
			(at 0 0 180)
			(unlocked yes)
			(layer "F.Fab")
			(hide yes)
			(effects
				(font
					(size 1 1)
					(thickness 0.15)
				)
			)
		)
		(property "Val" "100n"
			(at 0 0 180)
			(unlocked yes)
			(layer "F.Fab")
			(hide yes)
			(effects
				(font
					(size 1 1)
					(thickness 0.15)
				)
			)
		)
		(property "Voltage" "50V"
			(at 0 0 180)
			(unlocked yes)
			(layer "F.Fab")
			(hide yes)
			(effects
				(font
					(size 1 1)
					(thickness 0.15)
				)
			)
		)
		(property "Dielectric" "X5R"
			(at 0 0 180)
			(unlocked yes)
			(layer "F.Fab")
			(hide yes)
			(effects
				(font
					(size 1 1)
					(thickness 0.15)
				)
			)
		)
		(property "Public" "False"
			(at 0 0 180)
			(unlocked yes)
			(layer "F.Fab")
			(hide yes)
			(effects
				(font
					(size 1 1)
					(thickness 0.15)
				)
			)
		)
		(sheetname "/DCDC/")
		(sheetfile "dcdc.kicad_sch")
		(attr smd)
		(fp_rect
			(start -0.925 -0.47)
			(end 0.925 0.47)
			(stroke
				(width 0.05)
				(type default)
			)
			(fill no)
			(layer "F.CrtYd")
		)
		(fp_line
			(start 0.504 0.248)
			(end -0.494 0.248)
			(stroke
				(width 0.15)
				(type solid)
			)
			(layer "F.Fab")
		)
		(fp_line
			(start 0.504 -0.25)
			(end 0.504 0.248)
			(stroke
				(width 0.15)
				(type solid)
			)
			(layer "F.Fab")
		)
		(fp_line
			(start -0.494 0.248)
			(end -0.494 -0.25)
			(stroke
				(width 0.15)
				(type solid)
			)
			(layer "F.Fab")
		)
		(fp_line
			(start -0.494 -0.25)
			(end 0.504 -0.25)
			(stroke
				(width 0.15)
				(type solid)
			)
			(layer "F.Fab")
		)
		(fp_text user "${REFERENCE}"
			(at -0.939 4.599 0)
			(layer "F.Fab")
			(effects
				(font
					(size 0.7 0.7)
					(thickness 0.15)
				)
				(justify right top)
			)
		)
		(fp_text user "Author: Antmicro"
			(at -0.939 3.399 0)
			(layer "F.Fab")
			(effects
				(font
					(size 0.7 0.7)
					(thickness 0.15)
				)
				(justify right top)
			)
		)
		(fp_text user "License: Apache-2.0"
			(at -0.939 5.799 0)
			(layer "F.Fab")
			(effects
				(font
					(size 0.7 0.7)
					(thickness 0.15)
				)
				(justify right top)
			)
		)
		(pad "1" smd roundrect
			(at -0.48 0 180)
			(size 0.59 0.64)
			(layers "F.Cu" "F.Mask" "F.Paste")
			(roundrect_rratio 0.25)
			(net 1 "GND")
			(pintype "passive")
		)
		(pad "2" smd roundrect
			(at 0.48 0 180)
			(size 0.59 0.64)
			(layers "F.Cu" "F.Mask" "F.Paste")
			(roundrect_rratio 0.25)
			(net 4 "+3V3_AON")
			(pintype "passive")
		)
	)
	(footprint "antmicro-footprints:XSON-8_1x1.95mm_P0.5mm"
		(layer "F.Cu")
		(at 211.2 79.8 90)
		(property "Reference" "U31"
			(at -0.2 1.2 180)
			(layer "F.SilkS")
			(effects
				(font
					(size 0.7 0.7)
					(thickness 0.15)
				)
				(justify left bottom)
			)
		)
		(property "Value" "NTS0102_XSON"
			(at 0 2.2 90)
			(layer "F.Fab")
			(effects
				(font
					(size 0.7 0.7)
					(thickness 0.15)
				)
				(justify left bottom)
			)
		)
		(property "Datasheet" "http://www.farnell.com/datasheets/1760723.pdf"
			(at 0 0 90)
			(layer "F.Fab")
			(hide yes)
			(effects
				(font
					(size 1.27 1.27)
					(thickness 0.15)
				)
			)
		)
		(property "Description" "Transceiver, 1.65 V to 3.6 V, XSON-8"
			(at 0 0 90)
			(layer "F.Fab")
			(hide yes)
			(effects
				(font
					(size 1.27 1.27)
					(thickness 0.15)
				)
			)
		)
		(property "MPN" "NTS0102GT"
			(at 0 0 90)
			(unlocked yes)
			(layer "F.Fab")
			(hide yes)
			(effects
				(font
					(size 1 1)
					(thickness 0.15)
				)
			)
		)
		(property "Manufacturer" "NXP"
			(at 0 0 90)
			(unlocked yes)
			(layer "F.Fab")
			(hide yes)
			(effects
				(font
					(size 1 1)
					(thickness 0.15)
				)
			)
		)
		(property "Author" "Antmicro"
			(at 0 0 90)
			(unlocked yes)
			(layer "F.Fab")
			(hide yes)
			(effects
				(font
					(size 1 1)
					(thickness 0.15)
				)
			)
		)
		(property "License" "Apache-2.0"
			(at 0 0 90)
			(unlocked yes)
			(layer "F.Fab")
			(hide yes)
			(effects
				(font
					(size 1 1)
					(thickness 0.15)
				)
			)
		)
		(sheetname "/USB Debug, PD/")
		(sheetfile "usb_debug_pd.kicad_sch")
		(attr smd)
		(fp_line
			(start -0.5 -1.1)
			(end 0.5 -1.1)
			(stroke
				(width 0.15)
				(type solid)
			)
			(layer "F.SilkS")
		)
		(fp_line
			(start 0.5 1.1)
			(end -0.5 1.1)
			(stroke
				(width 0.15)
				(type solid)
			)
			(layer "F.SilkS")
		)
		(fp_circle
			(center -0.750001 -1.1)
			(end -0.700999 -1.1)
			(stroke
				(width 0.15)
				(type solid)
			)
			(fill no)
			(layer "F.SilkS")
		)
		(fp_poly
			(pts
				(xy -0.8 -1.200001) (xy 0.8 -1.200001) (xy 0.8 1.200001) (xy -0.8 1.200001)
			)
			(stroke
				(width 0.05)
				(type solid)
			)
			(fill no)
			(layer "F.CrtYd")
		)
		(fp_line
			(start 0.5305 -1.001)
			(end 0.5305 1)
			(stroke
				(width 0.15)
				(type solid)
			)
			(layer "F.Fab")
		)
		(fp_line
			(start -0.5305 -1.001)
			(end 0.5305 -1.001)
			(stroke
				(width 0.15)
				(type solid)
			)
			(layer "F.Fab")
		)
		(fp_line
			(start 0.5305 1)
			(end -0.5305 1)
			(stroke
				(width 0.15)
				(type solid)
			)
			(layer "F.Fab")
		)
		(fp_line
			(start -0.5305 1)
			(end -0.5305 -1.001)
			(stroke
				(width 0.15)
				(type solid)
			)
			(layer "F.Fab")
		)
		(fp_text user "${REFERENCE}"
			(at -0.527 5.905 90)
			(layer "F.Fab")
			(effects
				(font
					(size 0.7 0.7)
					(thickness 0.15)
				)
				(justify left bottom)
			)
		)
		(fp_text user "License: Apache-2.0"
			(at -0.527 8.306 90)
			(layer "F.Fab")
			(effects
				(font
					(size 0.7 0.7)
					(thickness 0.15)
				)
				(justify left bottom)
			)
		)
		(fp_text user "Author: Antmicro"
			(at -0.527 7.105 90)
			(layer "F.Fab")
			(effects
				(font
					(size 0.7 0.7)
					(thickness 0.15)
				)
				(justify left bottom)
			)
		)
		(pad "1" smd roundrect
			(at -0.45 -0.75 270)
			(size 0.6 0.3)
			(layers "F.Cu" "F.Mask" "F.Paste")
			(roundrect_rratio 0.25)
			(net 945 "/USB Debug, PD/DEBUG_SCL")
			(pinfunction "B_{2}")
			(pintype "bidirectional")
		)
		(pad "2" smd roundrect
			(at -0.45 -0.25 270)
			(size 0.6 0.25)
			(layers "F.Cu" "F.Mask" "F.Paste")
			(roundrect_rratio 0.25)
			(net 1 "GND")
			(pinfunction "GND")
			(pintype "power_in")
		)
		(pad "3" smd roundrect
			(at -0.45 0.25 270)
			(size 0.6 0.25)
			(layers "F.Cu" "F.Mask" "F.Paste")
			(roundrect_rratio 0.25)
			(net 334 "/USB Debug, PD/FTDI_3V3")
			(pinfunction "VCC_{A}")
			(pintype "power_in")
		)
		(pad "4" smd roundrect
			(at -0.45 0.75 270)
			(size 0.6 0.3)
			(layers "F.Cu" "F.Mask" "F.Paste")
			(roundrect_rratio 0.25)
			(net 955 "/USB Debug, PD/FTDI_CBUS3{slash}SCL")
			(pinfunction "A_{2}")
			(pintype "bidirectional")
		)
		(pad "5" smd roundrect
			(at 0.45 0.75 270)
			(size 0.6 0.3)
			(layers "F.Cu" "F.Mask" "F.Paste")
			(roundrect_rratio 0.25)
			(net 956 "/USB Debug, PD/FTDI_CBUS0{slash}SDA")
			(pinfunction "A_{1}")
			(pintype "bidirectional")
		)
		(pad "6" smd roundrect
			(at 0.45 0.25 270)
			(size 0.6 0.25)
			(layers "F.Cu" "F.Mask" "F.Paste")
			(roundrect_rratio 0.25)
			(net 881 "/USB Debug, PD/FTDI_CBUS_EN")
			(pinfunction "OE")
			(pintype "input")
		)
		(pad "7" smd roundrect
			(at 0.45 -0.25 270)
			(size 0.6 0.25)
			(layers "F.Cu" "F.Mask" "F.Paste")
			(roundrect_rratio 0.25)
			(net 334 "/USB Debug, PD/FTDI_3V3")
			(pinfunction "VCC_{B}")
			(pintype "power_in")
		)
		(pad "8" smd roundrect
			(at 0.45 -0.75 270)
			(size 0.6 0.3)
			(layers "F.Cu" "F.Mask" "F.Paste")
			(roundrect_rratio 0.25)
			(net 946 "/USB Debug, PD/DEBUG_SDA")
			(pinfunction "B_{1}")
			(pintype "bidirectional")
		)
	)
	(footprint "antmicro-footprints:C_0402_1005Metric"
		(layer "F.Cu")
		(at 219.564132 86.75)
		(descr "Capacitor SMD 0402")
		(tags "capacitor SMD 0402")
		(property "Reference" "C142"
			(at -1.764132 -0.64 0)
			(layer "F.SilkS")
			(effects
				(font
					(size 0.7 0.7)
					(thickness 0.15)
				)
				(justify left bottom)
			)
		)
		(property "Value" "C_100n_0402"
			(at -1.022927 2.155213 0)
			(layer "F.Fab")
			(effects
				(font
					(size 0.7 0.7)
					(thickness 0.15)
				)
				(justify left bottom)
			)
		)
		(property "Datasheet" "https://www.murata.com/products/productdetail?partno=GRM155R61H104KE14%23"
			(at 0 0 0)
			(layer "F.Fab")
			(hide yes)
			(effects
				(font
					(size 1.27 1.27)
					(thickness 0.15)
				)
			)
		)
		(property "Description" "SMD Multilayer Ceramic Capacitor, 0.1 µF, 50 V, 0402 [1005 Metric], ± 10%, X5R, GRM Series"
			(at 0 0 0)
			(layer "F.Fab")
			(hide yes)
			(effects
				(font
					(size 1.27 1.27)
					(thickness 0.15)
				)
			)
		)
		(property "Manufacturer" "Murata"
			(at 0 0 0)
			(unlocked yes)
			(layer "F.Fab")
			(hide yes)
			(effects
				(font
					(size 1 1)
					(thickness 0.15)
				)
			)
		)
		(property "MPN" "GRM155R61H104KE14D"
			(at 0 0 0)
			(unlocked yes)
			(layer "F.Fab")
			(hide yes)
			(effects
				(font
					(size 1 1)
					(thickness 0.15)
				)
			)
		)
		(property "Val" "100n"
			(at 0 0 0)
			(unlocked yes)
			(layer "F.Fab")
			(hide yes)
			(effects
				(font
					(size 1 1)
					(thickness 0.15)
				)
			)
		)
		(property "License" "Apache-2.0"
			(at 0 0 0)
			(unlocked yes)
			(layer "F.Fab")
			(hide yes)
			(effects
				(font
					(size 1 1)
					(thickness 0.15)
				)
			)
		)
		(property "Author" "Antmicro"
			(at 0 0 0)
			(unlocked yes)
			(layer "F.Fab")
			(hide yes)
			(effects
				(font
					(size 1 1)
					(thickness 0.15)
				)
			)
		)
		(property "Voltage" "50V"
			(at 0 0 0)
			(unlocked yes)
			(layer "F.Fab")
			(hide yes)
			(effects
				(font
					(size 1 1)
					(thickness 0.15)
				)
			)
		)
		(property "Dielectric" "X5R"
			(at 0 0 0)
			(unlocked yes)
			(layer "F.Fab")
			(hide yes)
			(effects
				(font
					(size 1 1)
					(thickness 0.15)
				)
			)
		)
		(sheetname "/USB DP Alt mode/")
		(sheetfile "usb_dp.kicad_sch")
		(attr smd)
		(fp_rect
			(start -0.925 -0.47)
			(end 0.925 0.47)
			(stroke
				(width 0.05)
				(type default)
			)
			(fill no)
			(layer "F.CrtYd")
		)
		(fp_line
			(start -0.494 -0.25)
			(end 0.504 -0.25)
			(stroke
				(width 0.15)
				(type solid)
			)
			(layer "F.Fab")
		)
		(fp_line
			(start -0.494 0.248)
			(end -0.494 -0.25)
			(stroke
				(width 0.15)
				(type solid)
			)
			(layer "F.Fab")
		)
		(fp_line
			(start 0.504 -0.25)
			(end 0.504 0.248)
			(stroke
				(width 0.15)
				(type solid)
			)
			(layer "F.Fab")
		)
		(fp_line
			(start 0.504 0.248)
			(end -0.494 0.248)
			(stroke
				(width 0.15)
				(type solid)
			)
			(layer "F.Fab")
		)
		(fp_text user "${REFERENCE}"
			(at -0.939 4.599 0)
			(layer "F.Fab")
			(effects
				(font
					(size 0.7 0.7)
					(thickness 0.15)
				)
				(justify left bottom)
			)
		)
		(fp_text user "License: Apache-2.0"
			(at -0.939 5.799 0)
			(layer "F.Fab")
			(effects
				(font
					(size 0.7 0.7)
					(thickness 0.15)
				)
				(justify left bottom)
			)
		)
		(fp_text user "Author: Antmicro"
			(at -0.939 3.399 0)
			(layer "F.Fab")
			(effects
				(font
					(size 0.7 0.7)
					(thickness 0.15)
				)
				(justify left bottom)
			)
		)
		(pad "1" smd roundrect
			(at -0.48 0)
			(size 0.59 0.64)
			(layers "F.Cu" "F.Mask" "F.Paste")
			(roundrect_rratio 0.25)
			(net 354 "/USB DP Alt mode/USBC1_TX2_P")
			(pintype "passive")
		)
		(pad "2" smd roundrect
			(at 0.48 0)
			(size 0.59 0.64)
			(layers "F.Cu" "F.Mask" "F.Paste")
			(roundrect_rratio 0.25)
			(net 347 "/USB DP Alt mode/USBC1_CONN_TX2_P")
			(pintype "passive")
		)
	)
)
